# SCM (Grand Teton) — schematic netlist excerpt (pin names and nets, part order shuffled) for the footprints in the layout excerpt that follows; sources: Cadence DE-HDL packaged netlist, KiCad conversion of 12092022_DA0F0TMDCD0_F0T_Management_Board_D_brd_V3_OCP.brd

R479  Q_RES  33.2 1% CHIP  pkg 0402LF  page 15 : A = FM_P12V_HSC_ENABLE ; B = FM_P12V_HSC_ENABLE_R1
R99  Q_RES  0 5% CHIP  pkg 0402LF  page 52 : A = PWRGD_P3V3_RGM_R ; B = PWRGD_P3V3_RGM

(kicad_pcb
	(version 20260206)
	(generator "pcbnew")
	(generator_version "10.0")
	(general
		(thickness 1.6)
		(legacy_teardrops no)
	)
	(paper "A4")
	(title_block
		(title "12092022_DA0F0TMDCD0_F0T_Management_Board_D_brd_V3_OCP.brd")
		(comment 1 "Grand Teton / footprints 370-371 of 1440")
	)
	(layers
		(0 "F.Cu" signal "TOP")
		(4 "In1.Cu" signal "GND")
		(6 "In2.Cu" signal "IN1")
		(8 "In3.Cu" signal "GND1")
		(10 "In4.Cu" signal "IN2")
		(12 "In5.Cu" signal "VCC")
		(14 "In6.Cu" signal "VCC1")
		(16 "In7.Cu" signal "IN3")
		(18 "In8.Cu" signal "GND2")
		(20 "In9.Cu" signal "IN4")
		(22 "In10.Cu" signal "GND3")
		(2 "B.Cu" signal "BOTTOM")
		(9 "F.Adhes" user "F.Adhesive")
		(11 "B.Adhes" user "B.Adhesive")
		(13 "F.Paste" user "Package Geometry/Pastemask Top")
		(15 "B.Paste" user "Package Geometry/Pastemask Bottom")
		(5 "F.SilkS" user "Ref Des/Silkscreen Top")
		(7 "B.SilkS" user "Ref Des/Silkscreen Bottom")
		(1 "F.Mask" user "Board Geometry/Soldermask Top")
		(3 "B.Mask" user "Board Geometry/Soldermask Bottom")
		(17 "Dwgs.User" user "User.Drawings")
		(19 "Cmts.User" user "User.Comments")
		(21 "Eco1.User" user "User.Eco1")
		(23 "Eco2.User" user "User.Eco2")
		(25 "Edge.Cuts" user "Board Geometry/Outline")
		(27 "Margin" user)
		(31 "F.CrtYd" user "Package Geometry/Place Bound Top")
		(29 "B.CrtYd" user "Package Geometry/Place Bound Bottom")
		(35 "F.Fab" user "Ref Des/Assembly Top")
		(33 "B.Fab" user "Ref Des/Assembly Bottom")
	)
	(footprint ""
		(layer "F.Cu")
		(at 71.4375 -29.845 -90)
		(property "Reference" "R99"
			(at 0 0 270)
			(layer "F.SilkS")
			(hide yes)
			(effects
				(font
					(size 1.27 1.27)
				)
			)
		)
		(property "Value" ""
			(at 0 0 270)
			(layer "F.Fab")
			(effects
				(font
					(size 1.27 1.27)
				)
			)
		)
		(duplicate_pad_numbers_are_jumpers no)
		(fp_line
			(start -0.7874 0.4064)
			(end -0.7874 -0.4064)
			(stroke
				(width 0.1524)
				(type default)
			)
			(layer "F.SilkS")
		)
		(fp_line
			(start 0.7874 0.4064)
			(end -0.7874 0.4064)
			(stroke
				(width 0.1524)
				(type default)
			)
			(layer "F.SilkS")
		)
		(fp_line
			(start -0.7874 -0.4064)
			(end 0.7874 -0.4064)
			(stroke
				(width 0.1524)
				(type default)
			)
			(layer "F.SilkS")
		)
		(fp_line
			(start 0.7874 -0.4064)
			(end 0.7874 0.4064)
			(stroke
				(width 0.1524)
				(type default)
			)
			(layer "F.SilkS")
		)
		(fp_line
			(start -0.67945 0.3048)
			(end -0.67945 -0.305054)
			(stroke
				(width 0.1)
				(type default)
			)
			(layer "F.Fab")
		)
		(fp_line
			(start -0.12065 0.3048)
			(end -0.67945 0.3048)
			(stroke
				(width 0.1)
				(type default)
			)
			(layer "F.Fab")
		)
		(fp_line
			(start 0.120396 0.3048)
			(end 0.120396 0.2794)
			(stroke
				(width 0.1)
				(type default)
			)
			(layer "F.Fab")
		)
		(fp_line
			(start 0.67945 0.3048)
			(end 0.120396 0.3048)
			(stroke
				(width 0.1)
				(type default)
			)
			(layer "F.Fab")
		)
		(fp_line
			(start -0.12065 0.2794)
			(end -0.12065 0.3048)
			(stroke
				(width 0.1)
				(type default)
			)
			(layer "F.Fab")
		)
		(fp_line
			(start 0.120396 0.2794)
			(end -0.12065 0.2794)
			(stroke
				(width 0.1)
				(type default)
			)
			(layer "F.Fab")
		)
		(fp_line
			(start -0.12065 -0.2794)
			(end 0.12065 -0.2794)
			(stroke
				(width 0.1)
				(type default)
			)
			(layer "F.Fab")
		)
		(fp_line
			(start 0.12065 -0.2794)
			(end 0.12065 -0.3048)
			(stroke
				(width 0.1)
				(type default)
			)
			(layer "F.Fab")
		)
		(fp_line
			(start 0.12065 -0.3048)
			(end 0.67945 -0.3048)
			(stroke
				(width 0.1)
				(type default)
			)
			(layer "F.Fab")
		)
		(fp_line
			(start 0.67945 -0.3048)
			(end 0.67945 0.3048)
			(stroke
				(width 0.1)
				(type default)
			)
			(layer "F.Fab")
		)
		(fp_line
			(start -0.67945 -0.305054)
			(end -0.12065 -0.305054)
			(stroke
				(width 0.1)
				(type default)
			)
			(layer "F.Fab")
		)
		(fp_line
			(start -0.12065 -0.305054)
			(end -0.12065 -0.2794)
			(stroke
				(width 0.1)
				(type default)
			)
			(layer "F.Fab")
		)
		(pad "1" smd circle
			(at -0.40005 0 270)
			(size 0 0)
			(layers "F.Cu" "F.Mask" "F.Paste")
			(net "PWRGD_P3V3_RGM_R")
		)
		(pad "2" smd circle
			(at 0.40005 0 270)
			(size 0 0)
			(layers "F.Cu" "F.Mask" "F.Paste")
			(net "PWRGD_P3V3_RGM")
		)
	)
	(footprint ""
		(layer "F.Cu")
		(at 39.22776 -61.6585)
		(property "Reference" "R479"
			(at 0 0 0)
			(layer "F.SilkS")
			(hide yes)
			(effects
				(font
					(size 1.27 1.27)
				)
			)
		)
		(property "Value" ""
			(at 0 0 0)
			(layer "F.Fab")
			(effects
				(font
					(size 1.27 1.27)
				)
			)
		)
		(duplicate_pad_numbers_are_jumpers no)
		(fp_line
			(start -0.7874 -0.4064)
			(end 0.7874 -0.4064)
			(stroke
				(width 0.1524)
				(type default)
			)
			(layer "F.SilkS")
		)
		(fp_line
			(start -0.7874 0.4064)
			(end -0.7874 -0.4064)
			(stroke
				(width 0.1524)
				(type default)
			)
			(layer "F.SilkS")
		)
		(fp_line
			(start 0.7874 -0.4064)
			(end 0.7874 0.4064)
			(stroke
				(width 0.1524)
				(type default)
			)
			(layer "F.SilkS")
		)
		(fp_line
			(start 0.7874 0.4064)
			(end -0.7874 0.4064)
			(stroke
				(width 0.1524)
				(type default)
			)
			(layer "F.SilkS")
		)
		(fp_line
			(start -0.67945 -0.305054)
			(end -0.12065 -0.305054)
			(stroke
				(width 0.1)
				(type default)
			)
			(layer "F.Fab")
		)
		(fp_line
			(start -0.67945 0.3048)
			(end -0.67945 -0.305054)
			(stroke
				(width 0.1)
				(type default)
			)
			(layer "F.Fab")
		)
		(fp_line
			(start -0.12065 -0.305054)
			(end -0.12065 -0.2794)
			(stroke
				(width 0.1)
				(type default)
			)
			(layer "F.Fab")
		)
		(fp_line
			(start -0.12065 -0.2794)
			(end 0.12065 -0.2794)
			(stroke
				(width 0.1)
				(type default)
			)
			(layer "F.Fab")
		)
		(fp_line
			(start -0.12065 0.2794)
			(end -0.12065 0.3048)
			(stroke
				(width 0.1)
				(type default)
			)
			(layer "F.Fab")
		)
		(fp_line
			(start -0.12065 0.3048)
			(end -0.67945 0.3048)
			(stroke
				(width 0.1)
				(type default)
			)
			(layer "F.Fab")
		)
		(fp_line
			(start 0.120396 0.2794)
			(end -0.12065 0.2794)
			(stroke
				(width 0.1)
				(type default)
			)
			(layer "F.Fab")
		)
		(fp_line
			(start 0.120396 0.3048)
			(end 0.120396 0.2794)
			(stroke
				(width 0.1)
				(type default)
			)
			(layer "F.Fab")
		)
		(fp_line
			(start 0.12065 -0.3048)
			(end 0.67945 -0.3048)
			(stroke
				(width 0.1)
				(type default)
			)
			(layer "F.Fab")
		)
		(fp_line
			(start 0.12065 -0.2794)
			(end 0.12065 -0.3048)
			(stroke
				(width 0.1)
				(type default)
			)
			(layer "F.Fab")
		)
		(fp_line
			(start 0.67945 -0.3048)
			(end 0.67945 0.3048)
			(stroke
				(width 0.1)
				(type default)
			)
			(layer "F.Fab")
		)
		(fp_line
			(start 0.67945 0.3048)
			(end 0.120396 0.3048)
			(stroke
				(width 0.1)
				(type default)
			)
			(layer "F.Fab")
		)
		(pad "1" smd circle
			(at -0.40005 0)
			(size 0 0)
			(layers "F.Cu" "F.Mask" "F.Paste")
			(net "FM_P12V_HSC_ENABLE")
		)
		(pad "2" smd circle
			(at 0.40005 0)
			(size 0 0)
			(layers "F.Cu" "F.Mask" "F.Paste")
			(net "FM_P12V_HSC_ENABLE_R1")
		)
	)
)
